G04*
G04 #@! TF.GenerationSoftware,Altium Limited,Altium Designer,23.0.1 (38)*
G04*
G04 Layer_Color=8388736*
%FSLAX44Y44*%
%MOMM*%
G71*
G04*
G04 #@! TF.SameCoordinates,9A23C038-B079-480F-8166-AFFB5740F5AE*
G04*
G04*
G04 #@! TF.FilePolarity,Negative*
G04*
G01*
G75*
%ADD26R,5.0000X1.0000*%
%ADD27C,1.0000*%
%ADD30R,0.6000X0.5000*%
%ADD31C,1.1000*%
%ADD32R,1.3700X0.6588*%
%ADD33R,1.0000X0.7000*%
%ADD34R,0.6000X0.7000*%
%ADD35R,0.9000X0.9000*%
%ADD36R,0.9001X1.8983*%
%ADD37R,3.0500X1.1200*%
%ADD38R,0.6000X0.6000*%
%ADD39R,0.6000X0.6000*%
%ADD40R,0.7000X0.6000*%
%ADD41C,0.6500*%
G36*
X68400Y312495D02*
X68400Y271679D01*
Y269810D01*
X68180Y267663D01*
X66963Y263523D01*
X65011Y259674D01*
X62389Y256247D01*
X59186Y253355D01*
X55508Y251097D01*
X51481Y249548D01*
X47238Y248760D01*
X45080Y248760D01*
X4062D01*
X4058Y306760D01*
X4058Y307413D01*
X4313Y308693D01*
X4812Y309900D01*
X5537Y310985D01*
X6460Y311909D01*
X7545Y312635D01*
X8751Y313135D01*
X10031Y313391D01*
X10684Y313392D01*
X67502Y313393D01*
X68400Y312495D01*
D02*
G37*
G36*
X662899Y313154D02*
X664122Y312648D01*
X665223Y311913D01*
X666159Y310977D01*
X666895Y309878D01*
X667402Y308655D01*
X667661Y307358D01*
X667662Y306697D01*
X667656Y248746D01*
X612294Y248746D01*
X610485D01*
X606932Y249433D01*
X603575Y250781D01*
X600534Y252741D01*
X597920Y255243D01*
X595828Y258195D01*
X594334Y261490D01*
X593493Y265009D01*
X593414Y266816D01*
X593414Y279352D01*
X593414Y313410D01*
X660940Y313412D01*
X661602D01*
X662899Y313154D01*
D02*
G37*
G36*
X93560Y234306D02*
X93654Y234277D01*
X93741Y234231D01*
X93817Y234168D01*
X93879Y234092D01*
X93926Y234006D01*
X93954Y233911D01*
X93964Y233813D01*
Y210191D01*
X93954Y210093D01*
X93926Y209999D01*
X93879Y209912D01*
X93817Y209836D01*
X93741Y209774D01*
X93654Y209727D01*
X93560Y209698D01*
X93462Y209689D01*
X74316D01*
X74289Y209691D01*
X74262Y209692D01*
X74240Y209696D01*
X74218Y209698D01*
X74192Y209706D01*
X74166Y209712D01*
X74145Y209720D01*
X74124Y209727D01*
X74100Y209740D01*
X74075Y209750D01*
X74057Y209763D01*
X74037Y209774D01*
X74016Y209791D01*
X73994Y209806D01*
X73978Y209822D01*
X73961Y209836D01*
X73944Y209857D01*
X73925Y209876D01*
X72948Y211090D01*
X70734Y213266D01*
X68217Y215067D01*
X65453Y216458D01*
X62506Y217403D01*
X59449Y217882D01*
X56354D01*
X53297Y217403D01*
X50351Y216458D01*
X47586Y215067D01*
X45070Y213266D01*
X42856Y211090D01*
X41879Y209876D01*
X41860Y209857D01*
X41843Y209836D01*
X41825Y209822D01*
X41810Y209806D01*
X41787Y209791D01*
X41766Y209774D01*
X41747Y209763D01*
X41728Y209750D01*
X41704Y209740D01*
X41680Y209727D01*
X41658Y209720D01*
X41638Y209712D01*
X41611Y209706D01*
X41585Y209698D01*
X41563Y209696D01*
X41541Y209692D01*
X41514Y209691D01*
X41487Y209689D01*
X22342D01*
X22244Y209698D01*
X22150Y209727D01*
X22063Y209774D01*
X21986Y209836D01*
X21924Y209912D01*
X21878Y209999D01*
X21849Y210093D01*
X21839Y210191D01*
Y233813D01*
X21849Y233911D01*
X21878Y234006D01*
X21924Y234092D01*
X21986Y234168D01*
X22063Y234231D01*
X22150Y234277D01*
X22244Y234306D01*
X22342Y234316D01*
X93462D01*
X93560Y234306D01*
D02*
G37*
G36*
X58850Y207128D02*
X60519Y206796D01*
X60547Y206787D01*
X60613Y206768D01*
X62185Y206117D01*
X62185Y206117D01*
X62215Y206100D01*
X62272Y206070D01*
X62272Y206070D01*
X63686Y205125D01*
X63762Y205063D01*
X63762Y205062D01*
X64965Y203860D01*
X65028Y203783D01*
X65972Y202369D01*
X65973Y202369D01*
X66019Y202282D01*
X66670Y200711D01*
X66670Y200711D01*
X66699Y200616D01*
X67031Y198948D01*
X67040Y198850D01*
Y197999D01*
Y197149D01*
X67031Y197051D01*
X66699Y195382D01*
X66690Y195354D01*
X66670Y195288D01*
X66019Y193716D01*
X66019Y193716D01*
X66003Y193686D01*
X65973Y193629D01*
X65972Y193629D01*
X65027Y192215D01*
X64965Y192139D01*
X64965Y192139D01*
X63762Y190936D01*
X63686Y190873D01*
X62272Y189928D01*
X62272Y189928D01*
X62185Y189882D01*
X60613Y189231D01*
X60613Y189231D01*
X60519Y189202D01*
X58850Y188870D01*
X58752Y188861D01*
X57051D01*
X56953Y188870D01*
X55285Y189202D01*
X55256Y189211D01*
X55191Y189231D01*
X53619Y189882D01*
X53619Y189882D01*
X53589Y189898D01*
X53532Y189928D01*
X53532Y189928D01*
X52118Y190873D01*
X52041Y190936D01*
X52041Y190936D01*
X50838Y192139D01*
X50776Y192215D01*
X49831Y193629D01*
X49831Y193629D01*
X49784Y193716D01*
X49134Y195288D01*
X49134Y195288D01*
X49105Y195382D01*
X48773Y197051D01*
X48763Y197149D01*
Y197999D01*
Y198850D01*
X48773Y198948D01*
X49105Y200616D01*
X49114Y200645D01*
X49134Y200711D01*
X49784Y202282D01*
X49784Y202282D01*
X49801Y202312D01*
X49831Y202369D01*
X49831Y202369D01*
X50776Y203783D01*
X50838Y203860D01*
X50839Y203860D01*
X52041Y205063D01*
X52118Y205125D01*
X53532Y206070D01*
X53532Y206070D01*
X53619Y206117D01*
X55190Y206767D01*
X55191Y206768D01*
X55285Y206796D01*
X56953Y207128D01*
X57051Y207138D01*
X58752D01*
X58850Y207128D01*
D02*
G37*
G36*
X93560Y186300D02*
X93654Y186271D01*
X93741Y186225D01*
X93817Y186162D01*
X93879Y186086D01*
X93926Y186000D01*
X93954Y185905D01*
X93964Y185807D01*
Y162185D01*
X93954Y162087D01*
X93926Y161993D01*
X93879Y161906D01*
X93817Y161830D01*
X93741Y161768D01*
X93654Y161721D01*
X93560Y161692D01*
X93462Y161683D01*
X22342D01*
X22244Y161692D01*
X22150Y161721D01*
X22063Y161768D01*
X21986Y161830D01*
X21924Y161906D01*
X21878Y161993D01*
X21849Y162087D01*
X21839Y162185D01*
Y185807D01*
X21849Y185905D01*
X21878Y186000D01*
X21924Y186086D01*
X21986Y186162D01*
X22063Y186225D01*
X22150Y186271D01*
X22244Y186300D01*
X22342Y186310D01*
X41487D01*
X41514Y186307D01*
X41541Y186307D01*
X41563Y186302D01*
X41585Y186300D01*
X41612Y186292D01*
X41638Y186287D01*
X41658Y186278D01*
X41680Y186271D01*
X41704Y186258D01*
X41728Y186248D01*
X41747Y186236D01*
X41766Y186225D01*
X41788Y186208D01*
X41810Y186192D01*
X41825Y186177D01*
X41843Y186162D01*
X41860Y186141D01*
X41879Y186122D01*
X42856Y184908D01*
X45070Y182733D01*
X47586Y180931D01*
X50351Y179541D01*
X53297Y178595D01*
X56354Y178116D01*
X59449D01*
X62506Y178595D01*
X65453Y179541D01*
X68217Y180931D01*
X70734Y182733D01*
X72948Y184908D01*
X73925Y186122D01*
X73944Y186141D01*
X73961Y186162D01*
X73978Y186177D01*
X73994Y186192D01*
X74016Y186208D01*
X74037Y186225D01*
X74057Y186235D01*
X74075Y186248D01*
X74100Y186259D01*
X74124Y186271D01*
X74145Y186278D01*
X74166Y186287D01*
X74192Y186292D01*
X74218Y186300D01*
X74240Y186302D01*
X74262Y186307D01*
X74289Y186307D01*
X74316Y186310D01*
X93462Y186310D01*
X93560Y186300D01*
D02*
G37*
G36*
X56531Y68583D02*
X57536Y68430D01*
X58526Y68201D01*
X59495Y67899D01*
X60440Y67523D01*
X61353Y67078D01*
X62229Y66564D01*
X63065Y65986D01*
X63854Y65347D01*
X64593Y64649D01*
X65277Y63898D01*
X65903Y63097D01*
X66465Y62251D01*
X66963Y61365D01*
X67392Y60444D01*
X67750Y59493D01*
X68035Y58518D01*
X68246Y57524D01*
X68285Y57228D01*
X68410Y56010D01*
X68410Y56010D01*
X68410Y56010D01*
Y4973D01*
X67512Y4075D01*
X10450Y4078D01*
X10450Y4078D01*
X10450Y4078D01*
X9822D01*
X8591Y4323D01*
X7432Y4803D01*
X6388Y5501D01*
X5501Y6388D01*
X4803Y7432D01*
X4323Y8591D01*
X4078Y9822D01*
X4078Y10450D01*
X4078Y10450D01*
X4078Y10450D01*
X4074Y67762D01*
X4972Y68660D01*
X55010Y68660D01*
X55518Y68660D01*
X56531Y68583D01*
D02*
G37*
G36*
X667638Y67762D02*
X667632Y10150D01*
X667632Y10150D01*
X667632Y10150D01*
X667632Y9548D01*
X667397Y8368D01*
X666937Y7257D01*
X666269Y6256D01*
X665419Y5405D01*
X664419Y4736D01*
X663307Y4275D01*
X662128Y4039D01*
X661526Y4038D01*
X593410Y4042D01*
Y10043D01*
X593410Y51910D01*
X593498Y53590D01*
X594305Y56857D01*
X595713Y59913D01*
X597673Y62648D01*
X600114Y64964D01*
X602948Y66778D01*
X606073Y68025D01*
X609378Y68660D01*
X611060D01*
X611060Y68660D01*
X666740D01*
X667638Y67762D01*
D02*
G37*
%LPC*%
G36*
X30037Y308538D02*
X26983D01*
X26589Y308460D01*
X26188D01*
X23193Y307864D01*
X22822Y307711D01*
X22428Y307632D01*
X19607Y306464D01*
X19273Y306241D01*
X18902Y306087D01*
X16364Y304391D01*
X16079Y304107D01*
X15746Y303883D01*
X13586Y301724D01*
X13363Y301390D01*
X13079Y301106D01*
X11383Y298568D01*
X11229Y298197D01*
X11006Y297863D01*
X9838Y295042D01*
X9759Y294648D01*
X9606Y294277D01*
X9010Y291282D01*
Y290881D01*
X8932Y290487D01*
Y287433D01*
X9010Y287039D01*
Y286638D01*
X9606Y283643D01*
X9759Y283272D01*
X9838Y282878D01*
X11006Y280057D01*
X11229Y279723D01*
X11383Y279352D01*
X13079Y276814D01*
X13363Y276529D01*
X13586Y276196D01*
X15746Y274037D01*
X16079Y273813D01*
X16364Y273529D01*
X18902Y271833D01*
X19273Y271679D01*
X19607Y271456D01*
X22428Y270288D01*
X22822Y270209D01*
X23193Y270056D01*
X26188Y269460D01*
X26589D01*
X26983Y269382D01*
X30037D01*
X30431Y269460D01*
X30832D01*
X33827Y270056D01*
X34198Y270209D01*
X34592Y270288D01*
X37413Y271456D01*
X37747Y271679D01*
X38118Y271833D01*
X40656Y273529D01*
X40941Y273813D01*
X41274Y274037D01*
X43433Y276196D01*
X43657Y276530D01*
X43941Y276814D01*
X45637Y279352D01*
X45791Y279723D01*
X46014Y280057D01*
X47182Y282878D01*
X47261Y283272D01*
X47414Y283643D01*
X48010Y286638D01*
Y287039D01*
X48088Y287433D01*
Y290487D01*
X48010Y290881D01*
Y291282D01*
X47414Y294277D01*
X47261Y294648D01*
X47182Y295042D01*
X46014Y297863D01*
X45791Y298197D01*
X45637Y298568D01*
X43941Y301106D01*
X43657Y301391D01*
X43433Y301724D01*
X41274Y303883D01*
X40940Y304107D01*
X40656Y304391D01*
X38118Y306087D01*
X37747Y306241D01*
X37413Y306464D01*
X34592Y307632D01*
X34198Y307711D01*
X33827Y307864D01*
X30832Y308460D01*
X30431D01*
X30037Y308538D01*
D02*
G37*
G36*
X635037D02*
X631983D01*
X631589Y308460D01*
X631188D01*
X628193Y307864D01*
X627822Y307711D01*
X627428Y307632D01*
X624607Y306464D01*
X624273Y306241D01*
X623902Y306087D01*
X621363Y304391D01*
X621079Y304107D01*
X620746Y303883D01*
X618587Y301724D01*
X618363Y301390D01*
X618079Y301106D01*
X616383Y298568D01*
X616229Y298197D01*
X616006Y297863D01*
X614838Y295042D01*
X614759Y294648D01*
X614606Y294277D01*
X614010Y291282D01*
Y290881D01*
X613932Y290487D01*
Y288960D01*
Y287433D01*
X614010Y287039D01*
Y286638D01*
X614606Y283643D01*
X614759Y283272D01*
X614838Y282878D01*
X616006Y280057D01*
X616229Y279723D01*
X616383Y279352D01*
X618079Y276814D01*
X618363Y276529D01*
X618587Y276196D01*
X620746Y274037D01*
X621079Y273813D01*
X621363Y273529D01*
X623902Y271833D01*
X624273Y271679D01*
X624607Y271456D01*
X627428Y270288D01*
X627822Y270209D01*
X628193Y270056D01*
X631188Y269460D01*
X631589D01*
X631983Y269382D01*
X635037D01*
X635431Y269460D01*
X635832D01*
X638827Y270056D01*
X639198Y270209D01*
X639592Y270288D01*
X642413Y271456D01*
X642747Y271679D01*
X643118Y271833D01*
X645657Y273529D01*
X645941Y273813D01*
X646274Y274037D01*
X648434Y276196D01*
X648657Y276530D01*
X648941Y276814D01*
X650637Y279352D01*
X650791Y279723D01*
X651014Y280057D01*
X652182Y282878D01*
X652261Y283272D01*
X652414Y283643D01*
X653010Y286638D01*
Y287039D01*
X653088Y287433D01*
Y288960D01*
Y290487D01*
X653010Y290881D01*
Y291282D01*
X652414Y294277D01*
X652261Y294648D01*
X652182Y295042D01*
X651014Y297863D01*
X650791Y298197D01*
X650637Y298568D01*
X648941Y301106D01*
X648657Y301391D01*
X648434Y301724D01*
X646274Y303883D01*
X645940Y304107D01*
X645657Y304391D01*
X643118Y306087D01*
X642747Y306241D01*
X642413Y306464D01*
X639592Y307632D01*
X639198Y307711D01*
X638827Y307864D01*
X635832Y308460D01*
X635431D01*
X635037Y308538D01*
D02*
G37*
G36*
X30037Y48469D02*
X26983D01*
X26852Y48460D01*
X26721D01*
X26591Y48443D01*
X26460Y48434D01*
X26331Y48409D01*
X26201Y48391D01*
X23207Y47796D01*
X23080Y47762D01*
X22951Y47736D01*
X22827Y47694D01*
X22700Y47660D01*
X22579Y47610D01*
X22455Y47568D01*
X19634Y46399D01*
X19517Y46341D01*
X19395Y46291D01*
X19281Y46225D01*
X19164Y46167D01*
X19055Y46095D01*
X18941Y46029D01*
X16402Y44333D01*
X16298Y44253D01*
X16189Y44180D01*
X16091Y44093D01*
X15986Y44014D01*
X15893Y43921D01*
X15795Y43834D01*
X13636Y41675D01*
X13549Y41577D01*
X13456Y41484D01*
X13377Y41379D01*
X13290Y41281D01*
X13217Y41172D01*
X13137Y41068D01*
X11441Y38529D01*
X11375Y38415D01*
X11302Y38306D01*
X11244Y38189D01*
X11179Y38075D01*
X11129Y37954D01*
X11071Y37836D01*
X9902Y35015D01*
X9860Y34891D01*
X9810Y34770D01*
X9776Y34643D01*
X9734Y34519D01*
X9708Y34390D01*
X9674Y34263D01*
X9078Y31269D01*
X9061Y31138D01*
X9036Y31010D01*
X9027Y30879D01*
X9010Y30749D01*
Y30618D01*
X9001Y30487D01*
Y27433D01*
X9010Y27302D01*
Y27171D01*
X9027Y27041D01*
X9036Y26910D01*
X9061Y26782D01*
X9078Y26651D01*
X9674Y23657D01*
X9708Y23530D01*
X9734Y23401D01*
X9776Y23277D01*
X9810Y23150D01*
X9860Y23029D01*
X9902Y22905D01*
X11071Y20084D01*
X11129Y19966D01*
X11179Y19845D01*
X11245Y19731D01*
X11302Y19614D01*
X11375Y19505D01*
X11441Y19391D01*
X13137Y16852D01*
X13217Y16748D01*
X13290Y16639D01*
X13377Y16540D01*
X13456Y16436D01*
X13549Y16343D01*
X13636Y16245D01*
X15795Y14086D01*
X15893Y13999D01*
X15986Y13907D01*
X16091Y13827D01*
X16189Y13740D01*
X16298Y13667D01*
X16402Y13587D01*
X18941Y11891D01*
X19055Y11825D01*
X19164Y11753D01*
X19281Y11695D01*
X19395Y11629D01*
X19516Y11579D01*
X19634Y11521D01*
X22455Y10352D01*
X22579Y10310D01*
X22700Y10260D01*
X22827Y10226D01*
X22951Y10184D01*
X23080Y10158D01*
X23207Y10124D01*
X26201Y9528D01*
X26332Y9511D01*
X26460Y9486D01*
X26591Y9477D01*
X26721Y9460D01*
X26852D01*
X26983Y9451D01*
X30037D01*
X30168Y9460D01*
X30299D01*
X30429Y9477D01*
X30560Y9486D01*
X30688Y9511D01*
X30819Y9528D01*
X33813Y10124D01*
X33940Y10158D01*
X34069Y10184D01*
X34193Y10226D01*
X34320Y10260D01*
X34441Y10310D01*
X34565Y10352D01*
X37386Y11521D01*
X37503Y11579D01*
X37625Y11629D01*
X37739Y11695D01*
X37856Y11753D01*
X37965Y11825D01*
X38079Y11891D01*
X40618Y13587D01*
X40722Y13667D01*
X40831Y13740D01*
X40929Y13827D01*
X41034Y13907D01*
X41127Y13999D01*
X41225Y14086D01*
X43384Y16245D01*
X43471Y16343D01*
X43563Y16436D01*
X43643Y16540D01*
X43730Y16639D01*
X43803Y16748D01*
X43883Y16852D01*
X45579Y19391D01*
X45645Y19505D01*
X45718Y19614D01*
X45775Y19732D01*
X45841Y19845D01*
X45891Y19966D01*
X45949Y20084D01*
X47118Y22905D01*
X47160Y23029D01*
X47210Y23150D01*
X47244Y23277D01*
X47286Y23401D01*
X47312Y23530D01*
X47346Y23657D01*
X47941Y26651D01*
X47959Y26781D01*
X47984Y26910D01*
X47993Y27041D01*
X48010Y27171D01*
Y27302D01*
X48019Y27433D01*
Y30487D01*
X48010Y30618D01*
Y30749D01*
X47993Y30879D01*
X47984Y31010D01*
X47959Y31139D01*
X47941Y31269D01*
X47346Y34263D01*
X47312Y34390D01*
X47286Y34519D01*
X47244Y34643D01*
X47210Y34770D01*
X47160Y34891D01*
X47118Y35015D01*
X45949Y37836D01*
X45891Y37954D01*
X45841Y38075D01*
X45775Y38189D01*
X45718Y38306D01*
X45645Y38415D01*
X45579Y38529D01*
X43883Y41068D01*
X43803Y41172D01*
X43730Y41281D01*
X43643Y41379D01*
X43563Y41484D01*
X43471Y41577D01*
X43384Y41675D01*
X41225Y43834D01*
X41127Y43921D01*
X41034Y44014D01*
X40929Y44093D01*
X40831Y44180D01*
X40722Y44253D01*
X40618Y44333D01*
X38079Y46029D01*
X37965Y46095D01*
X37856Y46167D01*
X37738Y46226D01*
X37625Y46291D01*
X37504Y46341D01*
X37386Y46399D01*
X34565Y47568D01*
X34441Y47610D01*
X34320Y47660D01*
X34193Y47694D01*
X34069Y47736D01*
X33940Y47762D01*
X33813Y47796D01*
X30819Y48391D01*
X30689Y48409D01*
X30560Y48434D01*
X30429Y48443D01*
X30299Y48460D01*
X30168D01*
X30037Y48469D01*
D02*
G37*
G36*
X635037Y48538D02*
X631983D01*
X631589Y48460D01*
X631188D01*
X628193Y47864D01*
X627822Y47711D01*
X627428Y47632D01*
X624607Y46464D01*
X624273Y46241D01*
X623902Y46087D01*
X621363Y44391D01*
X621079Y44107D01*
X620746Y43884D01*
X618587Y41725D01*
X618363Y41391D01*
X618079Y41107D01*
X616383Y38568D01*
X616229Y38197D01*
X616006Y37863D01*
X614838Y35042D01*
X614759Y34648D01*
X614606Y34277D01*
X614010Y31282D01*
Y30881D01*
X613932Y30487D01*
Y27433D01*
X614010Y27039D01*
Y26638D01*
X614606Y23643D01*
X614759Y23272D01*
X614838Y22878D01*
X616006Y20057D01*
X616229Y19723D01*
X616383Y19352D01*
X618079Y16813D01*
X618363Y16529D01*
X618587Y16195D01*
X620746Y14037D01*
X621079Y13813D01*
X621363Y13529D01*
X623902Y11833D01*
X624273Y11679D01*
X624607Y11456D01*
X627428Y10288D01*
X627822Y10209D01*
X628193Y10056D01*
X631188Y9460D01*
X631589D01*
X631983Y9382D01*
X635037D01*
X635431Y9460D01*
X635832D01*
X638827Y10056D01*
X639198Y10209D01*
X639592Y10288D01*
X642413Y11456D01*
X642747Y11679D01*
X643118Y11833D01*
X645657Y13529D01*
X645941Y13813D01*
X646274Y14037D01*
X648434Y16195D01*
X648657Y16530D01*
X648941Y16813D01*
X650637Y19352D01*
X650791Y19723D01*
X651014Y20057D01*
X652182Y22878D01*
X652261Y23272D01*
X652414Y23643D01*
X653010Y26638D01*
Y27039D01*
X653088Y27433D01*
Y30487D01*
X653010Y30881D01*
Y31282D01*
X652414Y34277D01*
X652261Y34648D01*
X652182Y35042D01*
X651014Y37863D01*
X650791Y38197D01*
X650637Y38568D01*
X648941Y41107D01*
X648657Y41391D01*
X648434Y41725D01*
X646274Y43884D01*
X645940Y44107D01*
X645657Y44391D01*
X643118Y46087D01*
X642747Y46241D01*
X642413Y46464D01*
X639592Y47632D01*
X639198Y47711D01*
X638827Y47864D01*
X635832Y48460D01*
X635431D01*
X635037Y48538D01*
D02*
G37*
%LPD*%
D26*
X57900Y168839D02*
D03*
X55360Y225940D02*
D03*
D27*
X57902Y197999D02*
D03*
D30*
X107877Y190000D02*
D03*
Y198000D02*
D03*
D31*
X610611Y216000D02*
D03*
X366000Y238000D02*
D03*
X333000Y253000D02*
D03*
X321999Y237146D02*
D03*
X311000Y253000D02*
D03*
X343995Y237146D02*
D03*
X248000Y72000D02*
D03*
X382000Y238000D02*
D03*
X305000Y72000D02*
D03*
X322000D02*
D03*
X585060Y216000D02*
D03*
D32*
X130652Y120850D02*
D03*
Y139150D02*
D03*
X111348Y130000D02*
D03*
D33*
X110000Y174384D02*
D03*
Y159383D02*
D03*
D34*
X95000Y104000D02*
D03*
X105000D02*
D03*
X382000Y254000D02*
D03*
X392000D02*
D03*
X136000Y104000D02*
D03*
X126000D02*
D03*
X221000Y72000D02*
D03*
X231000D02*
D03*
D35*
X510492Y112246D02*
D03*
Y97246D02*
D03*
X441492Y112246D02*
D03*
Y97246D02*
D03*
D36*
X311000Y215998D02*
D03*
X354993D02*
D03*
X365992D02*
D03*
X376990D02*
D03*
X321999D02*
D03*
X332997D02*
D03*
X343995D02*
D03*
X281003D02*
D03*
X248008D02*
D03*
X259007D02*
D03*
X270005D02*
D03*
X237010D02*
D03*
X270005Y94002D02*
D03*
X248008D02*
D03*
X237010D02*
D03*
X281003D02*
D03*
X259007D02*
D03*
X343995D02*
D03*
X332997D02*
D03*
X321999D02*
D03*
X376990D02*
D03*
X365992D02*
D03*
X354993D02*
D03*
X311000D02*
D03*
D37*
X633450Y82800D02*
D03*
Y102800D02*
D03*
Y122800D02*
D03*
Y142800D02*
D03*
X587950Y82800D02*
D03*
Y102800D02*
D03*
Y122800D02*
D03*
Y142800D02*
D03*
D38*
X138000Y174384D02*
D03*
X128000D02*
D03*
D39*
X352000Y62000D02*
D03*
Y72000D02*
D03*
X367557Y62000D02*
D03*
Y72000D02*
D03*
X382990Y62000D02*
D03*
Y72000D02*
D03*
X248008Y249000D02*
D03*
Y239000D02*
D03*
D40*
X293000Y248000D02*
D03*
Y238000D02*
D03*
X459000Y114000D02*
D03*
Y104000D02*
D03*
X528000Y114000D02*
D03*
Y104000D02*
D03*
X585060Y190000D02*
D03*
Y200000D02*
D03*
X610611Y190000D02*
D03*
Y200000D02*
D03*
D41*
X523000Y208039D02*
D03*
X522965Y242000D02*
D03*
X536000Y232691D02*
D03*
Y208000D02*
D03*
X561000Y103000D02*
D03*
Y123000D02*
D03*
X560000Y143000D02*
D03*
M02*
